# BASEBOARD_FAB2 (Tioga Pass) — schematic netlist excerpt (pin names and nets, part order shuffled) for the footprints in the layout excerpt that follows; sources: Cadence DE-HDL packaged netlist, KiCad conversion of Wiwynn_Tioga_Pass_MB.brd

C5G85  CAP_A  22.0UF 4V 20% X6S  pkg 0603V  page 243 : A = PVDDQ_GHJ ; B = GND
R8N5  RES  10.0K 1% CHIP  pkg 0402  page 55 : A = P3V3_STBY ; B = FM_CPU1_PKGID1
C9W6  CAP  1000PF 50V 10% EMPTY  pkg 0402LF  page 239 : A = PWRGD_P3V3_STBY ; B = GND

(kicad_pcb
	(version 20260206)
	(generator "pcbnew")
	(generator_version "10.0")
	(general
		(thickness 1.6)
		(legacy_teardrops no)
	)
	(paper "A4")
	(title_block
		(title "Wiwynn_Tioga_Pass_MB.brd")
		(comment 1 "Tioga Pass / footprints 2637-2639 of 4770")
	)
	(layers
		(0 "F.Cu" signal "TOP")
		(4 "In1.Cu" signal "L2GND")
		(6 "In2.Cu" signal "L3")
		(8 "In3.Cu" signal "L4GND")
		(10 "In4.Cu" signal "L5")
		(12 "In5.Cu" signal "L6GND")
		(14 "In6.Cu" signal "L7VCC")
		(16 "In7.Cu" signal "L8VCC")
		(18 "In8.Cu" signal "L9GND")
		(20 "In9.Cu" signal "L10")
		(22 "In10.Cu" signal "L11GND")
		(24 "In11.Cu" signal "L12")
		(26 "In12.Cu" signal "L13GND")
		(2 "B.Cu" signal "BOTTOM")
		(9 "F.Adhes" user "F.Adhesive")
		(11 "B.Adhes" user "B.Adhesive")
		(13 "F.Paste" user "Package Geometry/Pastemask Top")
		(15 "B.Paste" user "Package Geometry/Pastemask Bottom")
		(5 "F.SilkS" user "Ref Des/Silkscreen Top")
		(7 "B.SilkS" user "Ref Des/Silkscreen Bottom")
		(1 "F.Mask" user "Board Geometry/Soldermask Top")
		(3 "B.Mask" user "Board Geometry/Soldermask Bottom")
		(17 "Dwgs.User" user "User.Drawings")
		(19 "Cmts.User" user "User.Comments")
		(21 "Eco1.User" user "User.Eco1")
		(23 "Eco2.User" user "User.Eco2")
		(25 "Edge.Cuts" user "Board Geometry/Outline")
		(27 "Margin" user)
		(31 "F.CrtYd" user "Package Geometry/Place Bound Top")
		(29 "B.CrtYd" user "Package Geometry/Place Bound Bottom")
		(35 "F.Fab" user "Ref Des/Assembly Top")
		(33 "B.Fab" user "Ref Des/Assembly Bottom")
	)
	(footprint ""
		(layer "B.Cu")
		(at 88.392 -3.3528 90)
		(property "Reference" "C5G85"
			(at -1.14681 0.76708 180)
			(unlocked yes)
			(layer "B.SilkS")
			(effects
				(font
					(size 0.7874 0.5842)
					(thickness 0.1524)
				)
				(justify mirror)
			)
		)
		(property "Value" ""
			(at 0 0 90)
			(layer "B.Fab")
			(effects
				(font
					(size 1.27 1.27)
				)
				(justify mirror)
			)
		)
		(duplicate_pad_numbers_are_jumpers no)
		(fp_rect
			(start -0.4953 -0.2032)
			(end 0.4953 1.6002)
			(stroke
				(width 0)
				(type default)
			)
			(fill no)
			(layer "B.CrtYd")
		)
		(fp_line
			(start 0.4953 -0.2032)
			(end -0.4953 -0.2032)
			(stroke
				(width 0.1)
				(type default)
			)
			(layer "B.Fab")
		)
		(fp_line
			(start -0.4953 -0.2032)
			(end -0.4953 1.6002)
			(stroke
				(width 0.1)
				(type default)
			)
			(layer "B.Fab")
		)
		(fp_line
			(start 0.4953 1.6002)
			(end 0.4953 -0.2032)
			(stroke
				(width 0.1)
				(type default)
			)
			(layer "B.Fab")
		)
		(fp_line
			(start -0.4953 1.6002)
			(end 0.4953 1.6002)
			(stroke
				(width 0.1)
				(type default)
			)
			(layer "B.Fab")
		)
		(pad "1" smd rect
			(at 0 0 270)
			(size 0.762 0.889)
			(layers "B.Cu" "B.Mask" "B.Paste")
			(net "PVDDQ_GHJ")
		)
		(pad "2" smd rect
			(at 0 1.397 270)
			(size 0.762 0.889)
			(layers "B.Cu" "B.Mask" "B.Paste")
			(net "GND")
		)
		(zone
			(layer "B.Cu")
			(hatch none 0.5)
			(connect_pads
				(clearance 0)
			)
			(min_thickness 0.25)
			(keepout
				(tracks not_allowed)
				(vias allowed)
				(pads allowed)
				(copperpour not_allowed)
				(footprints allowed)
			)
			(placement
				(enabled no)
				(sheetname "")
			)
			(fill
				(thermal_gap 0.5)
				(thermal_bridge_width 0.5)
				(island_removal_mode 0)
			)
			(polygon
				(pts
					(xy 88.8365 -2.9718) (xy 89.3445 -2.9718) (xy 89.3445 -3.7338) (xy 88.8365 -3.7338)
				)
			)
		)
	)
	(footprint ""
		(layer "B.Cu")
		(at 457.533756 -21.494242 90)
		(property "Reference" "C9W6"
			(at 0.8382 -0.67818 90)
			(unlocked yes)
			(layer "B.SilkS")
			(effects
				(font
					(size 0.4064 0.254)
					(thickness 0.1524)
				)
				(justify left mirror)
			)
		)
		(property "Value" ""
			(at 0 0 90)
			(layer "B.Fab")
			(effects
				(font
					(size 1.27 1.27)
				)
				(justify mirror)
			)
		)
		(duplicate_pad_numbers_are_jumpers no)
		(fp_poly
			(pts
				(xy -0.3048 -0.1016) (xy -0.3048 0.9906) (xy 0.3048 0.9906) (xy 0.3048 -0.1016)
			)
			(stroke
				(width 0)
				(type default)
			)
			(fill no)
			(layer "B.CrtYd")
		)
		(fp_line
			(start 0.3048 -0.1016)
			(end 0.3048 0.9906)
			(stroke
				(width 0.1)
				(type default)
			)
			(layer "B.Fab")
		)
		(fp_line
			(start -0.3048 -0.1016)
			(end 0.3048 -0.1016)
			(stroke
				(width 0.1)
				(type default)
			)
			(layer "B.Fab")
		)
		(fp_line
			(start 0.3048 0.9906)
			(end -0.3048 0.9906)
			(stroke
				(width 0.1)
				(type default)
			)
			(layer "B.Fab")
		)
		(fp_line
			(start -0.3048 0.9906)
			(end -0.3048 -0.1016)
			(stroke
				(width 0.1)
				(type default)
			)
			(layer "B.Fab")
		)
		(pad "1" smd rect
			(at 0 0 270)
			(size 0.508 0.508)
			(layers "B.Cu" "B.Mask" "B.Paste")
			(net "PWRGD_P3V3_STBY")
		)
		(pad "2" smd rect
			(at 0 0.889 270)
			(size 0.508 0.508)
			(layers "B.Cu" "B.Mask" "B.Paste")
			(net "GND")
		)
		(zone
			(layer "B.Cu")
			(hatch none 0.5)
			(connect_pads
				(clearance 0)
			)
			(min_thickness 0.25)
			(keepout
				(tracks allowed)
				(vias not_allowed)
				(pads allowed)
				(copperpour not_allowed)
				(footprints allowed)
			)
			(placement
				(enabled no)
				(sheetname "")
			)
			(fill
				(thermal_gap 0.5)
				(thermal_bridge_width 0.5)
				(island_removal_mode 0)
			)
			(polygon
				(pts
					(xy 457.787756 -21.748242) (xy 457.787756 -21.240242) (xy 458.168756 -21.240242) (xy 458.168756 -21.748242)
				)
			)
		)
		(zone
			(layer "B.Cu")
			(hatch none 0.5)
			(connect_pads
				(clearance 0)
			)
			(min_thickness 0.25)
			(keepout
				(tracks not_allowed)
				(vias allowed)
				(pads allowed)
				(copperpour not_allowed)
				(footprints allowed)
			)
			(placement
				(enabled no)
				(sheetname "")
			)
			(fill
				(thermal_gap 0.5)
				(thermal_bridge_width 0.5)
				(island_removal_mode 0)
			)
			(polygon
				(pts
					(xy 458.168756 -21.748242) (xy 458.168756 -21.240242) (xy 457.787756 -21.240242) (xy 457.787756 -21.748242)
				)
			)
		)
	)
	(footprint ""
		(layer "B.Cu")
		(at 63.2968 -88.8492 90)
		(property "Reference" "R8N5"
			(at 0 0 90)
			(layer "B.SilkS")
			(hide yes)
			(effects
				(font
					(size 1.27 1.27)
				)
				(justify mirror)
			)
		)
		(property "Value" ""
			(at 0 0 90)
			(layer "B.Fab")
			(effects
				(font
					(size 1.27 1.27)
				)
				(justify mirror)
			)
		)
		(duplicate_pad_numbers_are_jumpers no)
		(fp_poly
			(pts
				(xy 0.2794 -0.1016) (xy -0.2794 -0.1016) (xy -0.2794 0.9906) (xy 0.2794 0.9906)
			)
			(stroke
				(width 0)
				(type default)
			)
			(fill no)
			(layer "B.CrtYd")
		)
		(fp_line
			(start 0.2794 -0.1016)
			(end 0.2794 0.9906)
			(stroke
				(width 0.1)
				(type default)
			)
			(layer "B.Fab")
		)
		(fp_line
			(start -0.2794 -0.1016)
			(end 0.2794 -0.1016)
			(stroke
				(width 0.1)
				(type default)
			)
			(layer "B.Fab")
		)
		(fp_line
			(start 0.2794 0.9906)
			(end -0.2794 0.9906)
			(stroke
				(width 0.1)
				(type default)
			)
			(layer "B.Fab")
		)
		(fp_line
			(start -0.2794 0.9906)
			(end -0.2794 -0.1016)
			(stroke
				(width 0.1)
				(type default)
			)
			(layer "B.Fab")
		)
		(pad "1" smd rect
			(at 0 0 270)
			(size 0.508 0.508)
			(layers "B.Cu" "B.Mask" "B.Paste")
			(net "P3V3_STBY")
		)
		(pad "2" smd rect
			(at 0 0.889 270)
			(size 0.508 0.508)
			(layers "B.Cu" "B.Mask" "B.Paste")
			(net "FM_CPU1_PKGID1")
		)
		(zone
			(layer "B.Cu")
			(hatch none 0.5)
			(connect_pads
				(clearance 0)
			)
			(min_thickness 0.25)
			(keepout
				(tracks allowed)
				(vias not_allowed)
				(pads allowed)
				(copperpour not_allowed)
				(footprints allowed)
			)
			(placement
				(enabled no)
				(sheetname "")
			)
			(fill
				(thermal_gap 0.5)
				(thermal_bridge_width 0.5)
				(island_removal_mode 0)
			)
			(polygon
				(pts
					(xy 63.5508 -89.1032) (xy 63.5508 -88.5952) (xy 63.9318 -88.5952) (xy 63.9318 -89.1032)
				)
			)
		)
		(zone
			(layer "B.Cu")
			(hatch none 0.5)
			(connect_pads
				(clearance 0)
			)
			(min_thickness 0.25)
			(keepout
				(tracks not_allowed)
				(vias allowed)
				(pads allowed)
				(copperpour not_allowed)
				(footprints allowed)
			)
			(placement
				(enabled no)
				(sheetname "")
			)
			(fill
				(thermal_gap 0.5)
				(thermal_bridge_width 0.5)
				(island_removal_mode 0)
			)
			(polygon
				(pts
					(xy 63.9318 -89.1032) (xy 63.9318 -88.5952) (xy 63.5508 -88.5952) (xy 63.5508 -89.1032)
				)
			)
		)
	)
)
